# T6G (Grand Teton) — schematic netlist excerpt (pin names and nets, part order shuffled) for the footprints in the layout excerpt that follows; sources: Cadence DE-HDL packaged netlist, KiCad conversion of 04192023_DAF0TMB3IC0_F0TG_MB_C_brd_V02_OCP.brd

PC2347  Q_CAP  1NF 50V 10% EMPTY  pkg 0402  page 263 : A = HSC_OCREF ; B = AGND_HSC
C508  Q_CAP  0.1UF 25V 10% X7R  pkg 0402  page 145 : A = P3V3_E1S_0 ; B = GND

(kicad_pcb
	(version 20260206)
	(generator "pcbnew")
	(generator_version "10.0")
	(general
		(thickness 1.6)
		(legacy_teardrops no)
	)
	(paper "A4")
	(title_block
		(title "04192023_DAF0TMB3IC0_F0TG_MB_C_brd_V02_OCP.brd")
		(comment 1 "Grand Teton / footprints 1690-1691 of 8354")
	)
	(layers
		(0 "F.Cu" signal "TOP")
		(4 "In1.Cu" signal "GND")
		(6 "In2.Cu" signal "IN1")
		(8 "In3.Cu" signal "GND1")
		(10 "In4.Cu" signal "IN2")
		(12 "In5.Cu" signal "GND2")
		(14 "In6.Cu" signal "IN3")
		(16 "In7.Cu" signal "GND3")
		(18 "In8.Cu" signal "VCC")
		(20 "In9.Cu" signal "VCC1")
		(22 "In10.Cu" signal "GND4")
		(24 "In11.Cu" signal "IN4")
		(26 "In12.Cu" signal "GND5")
		(28 "In13.Cu" signal "IN5")
		(30 "In14.Cu" signal "GND6")
		(32 "In15.Cu" signal "IN6")
		(34 "In16.Cu" signal "GND7")
		(2 "B.Cu" signal "BOTTOM")
		(9 "F.Adhes" user "F.Adhesive")
		(11 "B.Adhes" user "B.Adhesive")
		(13 "F.Paste" user "Package Geometry/Pastemask Top")
		(15 "B.Paste" user "Package Geometry/Pastemask Bottom")
		(5 "F.SilkS" user "Ref Des/Silkscreen Top")
		(7 "B.SilkS" user "Ref Des/Silkscreen Bottom")
		(1 "F.Mask" user "Board Geometry/Soldermask Top")
		(3 "B.Mask" user "Board Geometry/Soldermask Bottom")
		(17 "Dwgs.User" user "User.Drawings")
		(19 "Cmts.User" user "User.Comments")
		(21 "Eco1.User" user "User.Eco1")
		(23 "Eco2.User" user "User.Eco2")
		(25 "Edge.Cuts" user "Board Geometry/Outline")
		(27 "Margin" user)
		(31 "F.CrtYd" user "Package Geometry/Place Bound Top")
		(29 "B.CrtYd" user "Package Geometry/Place Bound Bottom")
		(35 "F.Fab" user "Ref Des/Assembly Top")
		(33 "B.Fab" user "Ref Des/Assembly Bottom")
	)
	(footprint ""
		(layer "F.Cu")
		(at 194.217798 -398.940782 180)
		(property "Reference" "PC2347"
			(at 0 0 180)
			(layer "F.SilkS")
			(hide yes)
			(effects
				(font
					(size 1.27 1.27)
				)
			)
		)
		(property "Value" ""
			(at 0 0 180)
			(layer "F.Fab")
			(effects
				(font
					(size 1.27 1.27)
				)
			)
		)
		(duplicate_pad_numbers_are_jumpers no)
		(fp_line
			(start 0.7874 0.4064)
			(end -0.7874 0.4064)
			(stroke
				(width 0.1524)
				(type default)
			)
			(layer "F.SilkS")
		)
		(fp_line
			(start 0.7874 -0.4064)
			(end 0.7874 0.4064)
			(stroke
				(width 0.1524)
				(type default)
			)
			(layer "F.SilkS")
		)
		(fp_line
			(start -0.7874 0.4064)
			(end -0.7874 -0.4064)
			(stroke
				(width 0.1524)
				(type default)
			)
			(layer "F.SilkS")
		)
		(fp_line
			(start -0.7874 -0.4064)
			(end 0.7874 -0.4064)
			(stroke
				(width 0.1524)
				(type default)
			)
			(layer "F.SilkS")
		)
		(fp_line
			(start 0.67945 0.3048)
			(end 0.120396 0.3048)
			(stroke
				(width 0.1)
				(type default)
			)
			(layer "F.Fab")
		)
		(fp_line
			(start 0.67945 -0.3048)
			(end 0.67945 0.3048)
			(stroke
				(width 0.1)
				(type default)
			)
			(layer "F.Fab")
		)
		(fp_line
			(start 0.12065 -0.2794)
			(end 0.12065 -0.3048)
			(stroke
				(width 0.1)
				(type default)
			)
			(layer "F.Fab")
		)
		(fp_line
			(start 0.12065 -0.3048)
			(end 0.67945 -0.3048)
			(stroke
				(width 0.1)
				(type default)
			)
			(layer "F.Fab")
		)
		(fp_line
			(start 0.120396 0.3048)
			(end 0.120396 0.2794)
			(stroke
				(width 0.1)
				(type default)
			)
			(layer "F.Fab")
		)
		(fp_line
			(start 0.120396 0.2794)
			(end -0.12065 0.2794)
			(stroke
				(width 0.1)
				(type default)
			)
			(layer "F.Fab")
		)
		(fp_line
			(start -0.12065 0.3048)
			(end -0.67945 0.3048)
			(stroke
				(width 0.1)
				(type default)
			)
			(layer "F.Fab")
		)
		(fp_line
			(start -0.12065 0.2794)
			(end -0.12065 0.3048)
			(stroke
				(width 0.1)
				(type default)
			)
			(layer "F.Fab")
		)
		(fp_line
			(start -0.12065 -0.2794)
			(end 0.12065 -0.2794)
			(stroke
				(width 0.1)
				(type default)
			)
			(layer "F.Fab")
		)
		(fp_line
			(start -0.12065 -0.305054)
			(end -0.12065 -0.2794)
			(stroke
				(width 0.1)
				(type default)
			)
			(layer "F.Fab")
		)
		(fp_line
			(start -0.67945 0.3048)
			(end -0.67945 -0.305054)
			(stroke
				(width 0.1)
				(type default)
			)
			(layer "F.Fab")
		)
		(fp_line
			(start -0.67945 -0.305054)
			(end -0.12065 -0.305054)
			(stroke
				(width 0.1)
				(type default)
			)
			(layer "F.Fab")
		)
		(pad "1" smd circle
			(at -0.40005 0 180)
			(size 0 0)
			(layers "F.Cu" "F.Mask" "F.Paste")
			(net "HSC_OCREF")
		)
		(pad "2" smd circle
			(at 0.40005 0 180)
			(size 0 0)
			(layers "F.Cu" "F.Mask" "F.Paste")
			(net "AGND_HSC")
		)
	)
	(footprint ""
		(layer "F.Cu")
		(at 235.068872 -67.474338 -90)
		(property "Reference" "C508"
			(at 0 0 270)
			(layer "F.SilkS")
			(hide yes)
			(effects
				(font
					(size 1.27 1.27)
				)
			)
		)
		(property "Value" ""
			(at 0 0 270)
			(layer "F.Fab")
			(effects
				(font
					(size 1.27 1.27)
				)
			)
		)
		(duplicate_pad_numbers_are_jumpers no)
		(fp_line
			(start -0.7874 0.4064)
			(end -0.7874 -0.4064)
			(stroke
				(width 0.1524)
				(type default)
			)
			(layer "F.SilkS")
		)
		(fp_line
			(start 0.7874 0.4064)
			(end -0.7874 0.4064)
			(stroke
				(width 0.1524)
				(type default)
			)
			(layer "F.SilkS")
		)
		(fp_line
			(start -0.7874 -0.4064)
			(end 0.7874 -0.4064)
			(stroke
				(width 0.1524)
				(type default)
			)
			(layer "F.SilkS")
		)
		(fp_line
			(start 0.7874 -0.4064)
			(end 0.7874 0.4064)
			(stroke
				(width 0.1524)
				(type default)
			)
			(layer "F.SilkS")
		)
		(fp_line
			(start -0.67945 0.3048)
			(end -0.67945 -0.305054)
			(stroke
				(width 0.1)
				(type default)
			)
			(layer "F.Fab")
		)
		(fp_line
			(start -0.12065 0.3048)
			(end -0.67945 0.3048)
			(stroke
				(width 0.1)
				(type default)
			)
			(layer "F.Fab")
		)
		(fp_line
			(start 0.120396 0.3048)
			(end 0.120396 0.2794)
			(stroke
				(width 0.1)
				(type default)
			)
			(layer "F.Fab")
		)
		(fp_line
			(start 0.67945 0.3048)
			(end 0.120396 0.3048)
			(stroke
				(width 0.1)
				(type default)
			)
			(layer "F.Fab")
		)
		(fp_line
			(start -0.12065 0.2794)
			(end -0.12065 0.3048)
			(stroke
				(width 0.1)
				(type default)
			)
			(layer "F.Fab")
		)
		(fp_line
			(start 0.120396 0.2794)
			(end -0.12065 0.2794)
			(stroke
				(width 0.1)
				(type default)
			)
			(layer "F.Fab")
		)
		(fp_line
			(start -0.12065 -0.2794)
			(end 0.12065 -0.2794)
			(stroke
				(width 0.1)
				(type default)
			)
			(layer "F.Fab")
		)
		(fp_line
			(start 0.12065 -0.2794)
			(end 0.12065 -0.3048)
			(stroke
				(width 0.1)
				(type default)
			)
			(layer "F.Fab")
		)
		(fp_line
			(start 0.12065 -0.3048)
			(end 0.67945 -0.3048)
			(stroke
				(width 0.1)
				(type default)
			)
			(layer "F.Fab")
		)
		(fp_line
			(start 0.67945 -0.3048)
			(end 0.67945 0.3048)
			(stroke
				(width 0.1)
				(type default)
			)
			(layer "F.Fab")
		)
		(fp_line
			(start -0.67945 -0.305054)
			(end -0.12065 -0.305054)
			(stroke
				(width 0.1)
				(type default)
			)
			(layer "F.Fab")
		)
		(fp_line
			(start -0.12065 -0.305054)
			(end -0.12065 -0.2794)
			(stroke
				(width 0.1)
				(type default)
			)
			(layer "F.Fab")
		)
		(pad "1" smd circle
			(at -0.40005 0 270)
			(size 0 0)
			(layers "F.Cu" "F.Mask" "F.Paste")
			(net "P3V3_E1S_0")
		)
		(pad "2" smd circle
			(at 0.40005 0 270)
			(size 0 0)
			(layers "F.Cu" "F.Mask" "F.Paste")
			(net "GND")
		)
	)
)
